(kicad_pcb
	(version 20260206)
	(generator "pcbnew")
	(generator_version "10.0")
	(general
		(thickness 1.6)
		(legacy_teardrops no)
	)
	(paper "A4")
	(title_block
		(title "Wiwynn_Tioga_Pass_MB.brd")
		(comment 1 "Tioga Pass / footprints 3931-3937 of 4770")
	)
	(layers
		(0 "F.Cu" signal "TOP")
		(4 "In1.Cu" signal "L2GND")
		(6 "In2.Cu" signal "L3")
		(8 "In3.Cu" signal "L4GND")
		(10 "In4.Cu" signal "L5")
		(12 "In5.Cu" signal "L6GND")
		(14 "In6.Cu" signal "L7VCC")
		(16 "In7.Cu" signal "L8VCC")
		(18 "In8.Cu" signal "L9GND")
		(20 "In9.Cu" signal "L10")
		(22 "In10.Cu" signal "L11GND")
		(24 "In11.Cu" signal "L12")
		(26 "In12.Cu" signal "L13GND")
		(2 "B.Cu" signal "BOTTOM")
		(9 "F.Adhes" user "F.Adhesive")
		(11 "B.Adhes" user "B.Adhesive")
		(13 "F.Paste" user "Package Geometry/Pastemask Top")
		(15 "B.Paste" user "Package Geometry/Pastemask Bottom")
		(5 "F.SilkS" user "Ref Des/Silkscreen Top")
		(7 "B.SilkS" user "Ref Des/Silkscreen Bottom")
		(1 "F.Mask" user "Board Geometry/Soldermask Top")
		(3 "B.Mask" user "Board Geometry/Soldermask Bottom")
		(17 "Dwgs.User" user "User.Drawings")
		(19 "Cmts.User" user "User.Comments")
		(21 "Eco1.User" user "User.Eco1")
		(23 "Eco2.User" user "User.Eco2")
		(25 "Edge.Cuts" user "Board Geometry/Outline")
		(27 "Margin" user)
		(31 "F.CrtYd" user "Package Geometry/Place Bound Top")
		(29 "B.CrtYd" user "Package Geometry/Place Bound Bottom")
		(35 "F.Fab" user "Ref Des/Assembly Top")
		(33 "B.Fab" user "Ref Des/Assembly Bottom")
	)
	(footprint ""
		(layer "B.Cu")
		(at 214.503 -94.4372)
		(property "Reference" "C6N7"
			(at 0 0 0)
			(layer "B.SilkS")
			(hide yes)
			(effects
				(font
					(size 1.27 1.27)
				)
				(justify mirror)
			)
		)
		(property "Value" ""
			(at 0 0 0)
			(layer "B.Fab")
			(effects
				(font
					(size 1.27 1.27)
				)
				(justify mirror)
			)
		)
		(duplicate_pad_numbers_are_jumpers no)
		(fp_poly
			(pts
				(xy 0.4953 -0.2032) (xy -0.4953 -0.2032) (xy -0.4953 1.6002) (xy 0.4953 1.6002)
			)
			(stroke
				(width 0)
				(type default)
			)
			(fill no)
			(layer "B.CrtYd")
		)
		(fp_line
			(start -0.4953 -0.2032)
			(end -0.4953 1.6002)
			(stroke
				(width 0.1)
				(type default)
			)
			(layer "B.Fab")
		)
		(fp_line
			(start -0.4953 1.6002)
			(end 0.4953 1.6002)
			(stroke
				(width 0.1)
				(type default)
			)
			(layer "B.Fab")
		)
		(fp_line
			(start 0.4953 -0.2032)
			(end -0.4953 -0.2032)
			(stroke
				(width 0.1)
				(type default)
			)
			(layer "B.Fab")
		)
		(fp_line
			(start 0.4953 1.6002)
			(end 0.4953 -0.2032)
			(stroke
				(width 0.1)
				(type default)
			)
			(layer "B.Fab")
		)
		(pad "1" smd rect
			(at 0 0 180)
			(size 0.762 0.889)
			(layers "B.Cu" "B.Mask" "B.Paste")
			(net "PVSA_CPU0")
		)
		(pad "2" smd rect
			(at 0 1.397 180)
			(size 0.762 0.889)
			(layers "B.Cu" "B.Mask" "B.Paste")
			(net "GND")
		)
		(zone
			(layer "B.Cu")
			(hatch none 0.5)
			(connect_pads
				(clearance 0)
			)
			(min_thickness 0.25)
			(keepout
				(tracks not_allowed)
				(vias allowed)
				(pads allowed)
				(copperpour not_allowed)
				(footprints allowed)
			)
			(placement
				(enabled no)
				(sheetname "")
			)
			(fill
				(thermal_gap 0.5)
				(thermal_bridge_width 0.5)
				(island_removal_mode 0)
			)
			(polygon
				(pts
					(xy 214.884 -93.9927) (xy 214.122 -93.9927) (xy 214.122 -93.4847) (xy 214.884 -93.4847)
				)
			)
		)
	)
	(footprint ""
		(layer "B.Cu")
		(at 485.267 -48.5775)
		(property "Reference" "C1R13"
			(at 0 0 0)
			(layer "B.SilkS")
			(hide yes)
			(effects
				(font
					(size 1.27 1.27)
				)
				(justify mirror)
			)
		)
		(property "Value" ""
			(at 0 0 0)
			(layer "B.Fab")
			(effects
				(font
					(size 1.27 1.27)
				)
				(justify mirror)
			)
		)
		(duplicate_pad_numbers_are_jumpers no)
		(fp_poly
			(pts
				(xy 0.4953 -0.2032) (xy -0.4953 -0.2032) (xy -0.4953 1.6002) (xy 0.4953 1.6002)
			)
			(stroke
				(width 0)
				(type default)
			)
			(fill no)
			(layer "B.CrtYd")
		)
		(fp_line
			(start -0.4953 -0.2032)
			(end -0.4953 1.6002)
			(stroke
				(width 0.1)
				(type default)
			)
			(layer "B.Fab")
		)
		(fp_line
			(start -0.4953 1.6002)
			(end 0.4953 1.6002)
			(stroke
				(width 0.1)
				(type default)
			)
			(layer "B.Fab")
		)
		(fp_line
			(start 0.4953 -0.2032)
			(end -0.4953 -0.2032)
			(stroke
				(width 0.1)
				(type default)
			)
			(layer "B.Fab")
		)
		(fp_line
			(start 0.4953 1.6002)
			(end 0.4953 -0.2032)
			(stroke
				(width 0.1)
				(type default)
			)
			(layer "B.Fab")
		)
		(pad "1" smd rect
			(at 0 0 180)
			(size 0.762 0.889)
			(layers "B.Cu" "B.Mask" "B.Paste")
			(net "P3V3_STBY")
		)
		(pad "2" smd rect
			(at 0 1.397 180)
			(size 0.762 0.889)
			(layers "B.Cu" "B.Mask" "B.Paste")
			(net "GND")
		)
		(zone
			(layer "B.Cu")
			(hatch none 0.5)
			(connect_pads
				(clearance 0)
			)
			(min_thickness 0.25)
			(keepout
				(tracks not_allowed)
				(vias allowed)
				(pads allowed)
				(copperpour not_allowed)
				(footprints allowed)
			)
			(placement
				(enabled no)
				(sheetname "")
			)
			(fill
				(thermal_gap 0.5)
				(thermal_bridge_width 0.5)
				(island_removal_mode 0)
			)
			(polygon
				(pts
					(xy 485.648 -48.133) (xy 484.886 -48.133) (xy 484.886 -47.625) (xy 485.648 -47.625)
				)
			)
		)
	)
	(footprint ""
		(layer "B.Cu")
		(at 411.2895 -11.000994 90)
		(property "Reference" "R8E32"
			(at 0 0 90)
			(layer "B.SilkS")
			(hide yes)
			(effects
				(font
					(size 1.27 1.27)
				)
				(justify mirror)
			)
		)
		(property "Value" ""
			(at 0 0 90)
			(layer "B.Fab")
			(effects
				(font
					(size 1.27 1.27)
				)
				(justify mirror)
			)
		)
		(duplicate_pad_numbers_are_jumpers no)
		(fp_poly
			(pts
				(xy 0.2794 -0.1016) (xy -0.2794 -0.1016) (xy -0.2794 0.9906) (xy 0.2794 0.9906)
			)
			(stroke
				(width 0)
				(type default)
			)
			(fill no)
			(layer "B.CrtYd")
		)
		(fp_line
			(start 0.2794 -0.1016)
			(end 0.2794 0.9906)
			(stroke
				(width 0.1)
				(type default)
			)
			(layer "B.Fab")
		)
		(fp_line
			(start -0.2794 -0.1016)
			(end 0.2794 -0.1016)
			(stroke
				(width 0.1)
				(type default)
			)
			(layer "B.Fab")
		)
		(fp_line
			(start 0.2794 0.9906)
			(end -0.2794 0.9906)
			(stroke
				(width 0.1)
				(type default)
			)
			(layer "B.Fab")
		)
		(fp_line
			(start -0.2794 0.9906)
			(end -0.2794 -0.1016)
			(stroke
				(width 0.1)
				(type default)
			)
			(layer "B.Fab")
		)
		(pad "1" smd rect
			(at 0 0 270)
			(size 0.508 0.508)
			(layers "B.Cu" "B.Mask" "B.Paste")
			(net "P3V3_STBY")
		)
		(pad "2" smd rect
			(at 0 0.889 270)
			(size 0.508 0.508)
			(layers "B.Cu" "B.Mask" "B.Paste")
			(net "FP_NMI_BTN_OUT_R_N")
		)
		(zone
			(layer "B.Cu")
			(hatch none 0.5)
			(connect_pads
				(clearance 0)
			)
			(min_thickness 0.25)
			(keepout
				(tracks allowed)
				(vias not_allowed)
				(pads allowed)
				(copperpour not_allowed)
				(footprints allowed)
			)
			(placement
				(enabled no)
				(sheetname "")
			)
			(fill
				(thermal_gap 0.5)
				(thermal_bridge_width 0.5)
				(island_removal_mode 0)
			)
			(polygon
				(pts
					(xy 411.5435 -11.254994) (xy 411.5435 -10.746994) (xy 411.9245 -10.746994) (xy 411.9245 -11.254994)
				)
			)
		)
		(zone
			(layer "B.Cu")
			(hatch none 0.5)
			(connect_pads
				(clearance 0)
			)
			(min_thickness 0.25)
			(keepout
				(tracks not_allowed)
				(vias allowed)
				(pads allowed)
				(copperpour not_allowed)
				(footprints allowed)
			)
			(placement
				(enabled no)
				(sheetname "")
			)
			(fill
				(thermal_gap 0.5)
				(thermal_bridge_width 0.5)
				(island_removal_mode 0)
			)
			(polygon
				(pts
					(xy 411.9245 -11.254994) (xy 411.9245 -10.746994) (xy 411.5435 -10.746994) (xy 411.5435 -11.254994)
				)
			)
		)
	)
	(footprint ""
		(layer "B.Cu")
		(at 39.329614 -107.807506 -90)
		(property "Reference" "R1C1"
			(at 0 0 90)
			(layer "B.SilkS")
			(hide yes)
			(effects
				(font
					(size 1.27 1.27)
				)
				(justify mirror)
			)
		)
		(property "Value" ""
			(at 0 0 90)
			(layer "B.Fab")
			(effects
				(font
					(size 1.27 1.27)
				)
				(justify mirror)
			)
		)
		(duplicate_pad_numbers_are_jumpers no)
		(fp_poly
			(pts
				(xy 0.2794 -0.1016) (xy -0.2794 -0.1016) (xy -0.2794 0.9906) (xy 0.2794 0.9906)
			)
			(stroke
				(width 0)
				(type default)
			)
			(fill no)
			(layer "B.CrtYd")
		)
		(fp_line
			(start -0.2794 0.9906)
			(end -0.2794 -0.1016)
			(stroke
				(width 0.1)
				(type default)
			)
			(layer "B.Fab")
		)
		(fp_line
			(start 0.2794 0.9906)
			(end -0.2794 0.9906)
			(stroke
				(width 0.1)
				(type default)
			)
			(layer "B.Fab")
		)
		(fp_line
			(start -0.2794 -0.1016)
			(end 0.2794 -0.1016)
			(stroke
				(width 0.1)
				(type default)
			)
			(layer "B.Fab")
		)
		(fp_line
			(start 0.2794 -0.1016)
			(end 0.2794 0.9906)
			(stroke
				(width 0.1)
				(type default)
			)
			(layer "B.Fab")
		)
		(pad "1" smd rect
			(at 0 0 90)
			(size 0.508 0.508)
			(layers "B.Cu" "B.Mask" "B.Paste")
			(net "SVID_ALERT1_CPU1_N")
		)
		(pad "2" smd rect
			(at 0 0.889 90)
			(size 0.508 0.508)
			(layers "B.Cu" "B.Mask" "B.Paste")
			(net "SVID_ALERT1_CPU1_R_N")
		)
		(zone
			(layer "B.Cu")
			(hatch none 0.5)
			(connect_pads
				(clearance 0)
			)
			(min_thickness 0.25)
			(keepout
				(tracks not_allowed)
				(vias allowed)
				(pads allowed)
				(copperpour not_allowed)
				(footprints allowed)
			)
			(placement
				(enabled no)
				(sheetname "")
			)
			(fill
				(thermal_gap 0.5)
				(thermal_bridge_width 0.5)
				(island_removal_mode 0)
			)
			(polygon
				(pts
					(xy 38.694614 -107.553506) (xy 38.694614 -108.061506) (xy 39.075614 -108.061506) (xy 39.075614 -107.553506)
				)
			)
		)
		(zone
			(layer "B.Cu")
			(hatch none 0.5)
			(connect_pads
				(clearance 0)
			)
			(min_thickness 0.25)
			(keepout
				(tracks allowed)
				(vias not_allowed)
				(pads allowed)
				(copperpour not_allowed)
				(footprints allowed)
			)
			(placement
				(enabled no)
				(sheetname "")
			)
			(fill
				(thermal_gap 0.5)
				(thermal_bridge_width 0.5)
				(island_removal_mode 0)
			)
			(polygon
				(pts
					(xy 39.075614 -107.553506) (xy 39.075614 -108.061506) (xy 38.694614 -108.061506) (xy 38.694614 -107.553506)
				)
			)
		)
	)
	(footprint ""
		(layer "B.Cu")
		(at 13.84046 -107.48518 90)
		(property "Reference" "C9N3"
			(at 0 0 90)
			(layer "B.SilkS")
			(hide yes)
			(effects
				(font
					(size 1.27 1.27)
				)
				(justify mirror)
			)
		)
		(property "Value" ""
			(at 0 0 90)
			(layer "B.Fab")
			(effects
				(font
					(size 1.27 1.27)
				)
				(justify mirror)
			)
		)
		(duplicate_pad_numbers_are_jumpers no)
		(fp_poly
			(pts
				(xy -0.3048 -0.1016) (xy -0.3048 0.9906) (xy 0.3048 0.9906) (xy 0.3048 -0.1016)
			)
			(stroke
				(width 0)
				(type default)
			)
			(fill no)
			(layer "B.CrtYd")
		)
		(fp_line
			(start 0.3048 -0.1016)
			(end 0.3048 0.9906)
			(stroke
				(width 0.1)
				(type default)
			)
			(layer "B.Fab")
		)
		(fp_line
			(start -0.3048 -0.1016)
			(end 0.3048 -0.1016)
			(stroke
				(width 0.1)
				(type default)
			)
			(layer "B.Fab")
		)
		(fp_line
			(start 0.3048 0.9906)
			(end -0.3048 0.9906)
			(stroke
				(width 0.1)
				(type default)
			)
			(layer "B.Fab")
		)
		(fp_line
			(start -0.3048 0.9906)
			(end -0.3048 -0.1016)
			(stroke
				(width 0.1)
				(type default)
			)
			(layer "B.Fab")
		)
		(pad "1" smd rect
			(at 0 0 270)
			(size 0.508 0.508)
			(layers "B.Cu" "B.Mask" "B.Paste")
			(net "P3E_CPU1_PE3_MP_C_TXN<11>")
		)
		(pad "2" smd rect
			(at 0 0.889 270)
			(size 0.508 0.508)
			(layers "B.Cu" "B.Mask" "B.Paste")
			(net "P3E_CPU1_PE3_MP_TXN<11>")
		)
		(zone
			(layer "B.Cu")
			(hatch none 0.5)
			(connect_pads
				(clearance 0)
			)
			(min_thickness 0.25)
			(keepout
				(tracks allowed)
				(vias not_allowed)
				(pads allowed)
				(copperpour not_allowed)
				(footprints allowed)
			)
			(placement
				(enabled no)
				(sheetname "")
			)
			(fill
				(thermal_gap 0.5)
				(thermal_bridge_width 0.5)
				(island_removal_mode 0)
			)
			(polygon
				(pts
					(xy 14.09446 -107.73918) (xy 14.09446 -107.23118) (xy 14.47546 -107.23118) (xy 14.47546 -107.73918)
				)
			)
		)
		(zone
			(layer "B.Cu")
			(hatch none 0.5)
			(connect_pads
				(clearance 0)
			)
			(min_thickness 0.25)
			(keepout
				(tracks not_allowed)
				(vias allowed)
				(pads allowed)
				(copperpour not_allowed)
				(footprints allowed)
			)
			(placement
				(enabled no)
				(sheetname "")
			)
			(fill
				(thermal_gap 0.5)
				(thermal_bridge_width 0.5)
				(island_removal_mode 0)
			)
			(polygon
				(pts
					(xy 14.47546 -107.73918) (xy 14.47546 -107.23118) (xy 14.09446 -107.23118) (xy 14.09446 -107.73918)
				)
			)
		)
	)
	(footprint ""
		(layer "B.Cu")
		(at 430.4792 -22.5298 180)
		(property "Reference" "R1U23"
			(at 0 0 0)
			(layer "B.SilkS")
			(hide yes)
			(effects
				(font
					(size 1.27 1.27)
				)
				(justify mirror)
			)
		)
		(property "Value" ""
			(at 0 0 0)
			(layer "B.Fab")
			(effects
				(font
					(size 1.27 1.27)
				)
				(justify mirror)
			)
		)
		(duplicate_pad_numbers_are_jumpers no)
		(fp_poly
			(pts
				(xy 0.2794 -0.1016) (xy -0.2794 -0.1016) (xy -0.2794 0.9906) (xy 0.2794 0.9906)
			)
			(stroke
				(width 0)
				(type default)
			)
			(fill no)
			(layer "B.CrtYd")
		)
		(fp_line
			(start 0.2794 0.9906)
			(end -0.2794 0.9906)
			(stroke
				(width 0.1)
				(type default)
			)
			(layer "B.Fab")
		)
		(fp_line
			(start 0.2794 -0.1016)
			(end 0.2794 0.9906)
			(stroke
				(width 0.1)
				(type default)
			)
			(layer "B.Fab")
		)
		(fp_line
			(start -0.2794 0.9906)
			(end -0.2794 -0.1016)
			(stroke
				(width 0.1)
				(type default)
			)
			(layer "B.Fab")
		)
		(fp_line
			(start -0.2794 -0.1016)
			(end 0.2794 -0.1016)
			(stroke
				(width 0.1)
				(type default)
			)
			(layer "B.Fab")
		)
		(pad "1" smd rect
			(at 0 0)
			(size 0.508 0.508)
			(layers "B.Cu" "B.Mask" "B.Paste")
			(net "P3V3_STBY")
		)
		(pad "2" smd rect
			(at 0 0.889)
			(size 0.508 0.508)
			(layers "B.Cu" "B.Mask" "B.Paste")
			(net "FM_BOARD_SKU_ID0")
		)
		(zone
			(layer "B.Cu")
			(hatch none 0.5)
			(connect_pads
				(clearance 0)
			)
			(min_thickness 0.25)
			(keepout
				(tracks not_allowed)
				(vias allowed)
				(pads allowed)
				(copperpour not_allowed)
				(footprints allowed)
			)
			(placement
				(enabled no)
				(sheetname "")
			)
			(fill
				(thermal_gap 0.5)
				(thermal_bridge_width 0.5)
				(island_removal_mode 0)
			)
			(polygon
				(pts
					(xy 430.2252 -23.1648) (xy 430.7332 -23.1648) (xy 430.7332 -22.7838) (xy 430.2252 -22.7838)
				)
			)
		)
		(zone
			(layer "B.Cu")
			(hatch none 0.5)
			(connect_pads
				(clearance 0)
			)
			(min_thickness 0.25)
			(keepout
				(tracks allowed)
				(vias not_allowed)
				(pads allowed)
				(copperpour not_allowed)
				(footprints allowed)
			)
			(placement
				(enabled no)
				(sheetname "")
			)
			(fill
				(thermal_gap 0.5)
				(thermal_bridge_width 0.5)
				(island_removal_mode 0)
			)
			(polygon
				(pts
					(xy 430.2252 -22.7838) (xy 430.7332 -22.7838) (xy 430.7332 -23.1648) (xy 430.2252 -23.1648)
				)
			)
		)
	)
	(footprint ""
		(layer "B.Cu")
		(at 438.833006 -43.54195 180)
		(property "Reference" "R25W36"
			(at 0 0 0)
			(layer "B.SilkS")
			(hide yes)
			(effects
				(font
					(size 1.27 1.27)
				)
				(justify mirror)
			)
		)
		(property "Value" "*"
			(at -0.064008 -4.108196 180)
			(unlocked yes)
			(layer "B.Fab")
			(hide yes)
			(effects
				(font
					(size 1.27 1.016)
					(thickness 0.1524)
				)
				(justify mirror)
			)
		)
		(property "Device Type" "120R2F-GP_RCL_GP-120R2F-GP,64.A"
			(at -0.064008 -5.632196 180)
			(unlocked yes)
			(layer "B.Fab")
			(hide yes)
			(effects
				(font
					(size 1.27 1.016)
					(thickness 0.1524)
				)
				(justify mirror)
			)
		)
		(duplicate_pad_numbers_are_jumpers no)
		(fp_line
			(start 0.508 -0.9398)
			(end 0.508 0.9398)
			(stroke
				(width 0.1524)
				(type default)
			)
			(layer "B.SilkS")
		)
		(fp_line
			(start -0.508 -0.9398)
			(end 0.508 -0.9398)
			(stroke
				(width 0.1524)
				(type default)
			)
			(layer "B.SilkS")
		)
		(fp_rect
			(start 0.508 0.9398)
			(end -0.508 -0.9398)
			(stroke
				(width 0)
				(type default)
			)
			(fill no)
			(layer "B.CrtYd")
		)
		(fp_rect
			(start 0.508 0.9398)
			(end -0.508 -0.9398)
			(stroke
				(width 0)
				(type default)
			)
			(fill no)
			(layer "B.Fab")
		)
		(pad "1" smd custom
			(at 0 -0.4445)
			(size 0.1397 0.1397)
			(layers "B.Cu" "B.Mask" "B.Paste")
			(net "BMC_M_BA1")
			(options
				(clearance outline)
				(anchor circle)
			)
			(primitives
				(gr_poly
					(pts
						(arc
							(start -0.1778 0.2794)
							(mid -0.249642 0.249642)
							(end -0.2794 0.1778)
						)
						(arc
							(start -0.2794 -0.1778)
							(mid -0.249642 -0.249642)
							(end -0.1778 -0.2794)
						)
						(arc
							(start 0.1778 -0.2794)
							(mid 0.249642 -0.249642)
							(end 0.2794 -0.1778)
						)
						(arc
							(start 0.2794 0.1778)
							(mid 0.249642 0.249642)
							(end 0.1778 0.2794)
						)
					)
					(width 0)
					(fill yes)
				)
			)
		)
		(pad "2" smd custom
			(at 0 0.4445)
			(size 0.1397 0.1397)
			(layers "B.Cu" "B.Mask" "B.Paste")
			(net "P1V2_AUX_BMC")
			(options
				(clearance outline)
				(anchor circle)
			)
			(primitives
				(gr_poly
					(pts
						(arc
							(start -0.1778 0.2794)
							(mid -0.249642 0.249642)
							(end -0.2794 0.1778)
						)
						(arc
							(start -0.2794 -0.1778)
							(mid -0.249642 -0.249642)
							(end -0.1778 -0.2794)
						)
						(arc
							(start 0.1778 -0.2794)
							(mid 0.249642 -0.249642)
							(end 0.2794 -0.1778)
						)
						(arc
							(start 0.2794 0.1778)
							(mid 0.249642 0.249642)
							(end 0.1778 0.2794)
						)
					)
					(width 0)
					(fill yes)
				)
			)
		)
	)
)
